FILE_TYPE = CONNECTIVITY;
{Allegro Design Entry HDL 17.4-2019 S026 (4007227) 1/17/2022}
"PAGE_NUMBER" = 323;
0"NC";
1"GND\g";
2"GND\g";
3"GND\g";
4"GND\g";
5"GND\g";
6"GND\g";
7"GND\g";
8"P3V3_E1S_0_R\g";
9"P3V3_AUX\g";
10"P3V3_AUX\g";
11"GND\g";
12"GND\g";
13"GND\g";
14"GND\g";
15"GND\g";
16"P3V3_E1S_0_R\g";
17"GND\g";
18"P12V_E1S_0\g";
19"P12V_AUX\g";
20"P12V_E1S_AVIN_PD_0";
21"P12V_E1S_OV_FB_0";
22"HP_LVC3_E1S_0_HSC_PWRGD";
23"P12V_E1S_FLTB_0";
24"P12V_E1S_IMON_0";
25"P12V_E1S_EN_0_R2";
26"GND\g";
27"P12V_E1S_TIMER_0";
28"P12V_E1S_ISET_0";
29"P12V_E1S_SS_0";
30"GND\g";
31"P3V3_AUX\g";
32"GND\g";
33"GND\g";
34"GND\g";
35"GND\g";
36"P12V_AUX\g";
37"P3V3_E1S_0_R\g";
38"P12V_E1S_0_ISENSE_MPS_MAM";
39"P12V_E1S_0_ISENSE_MPS_TIC";
40"P3V3_E1S_MODE_0";
41"P12V_E1S_ISET_0_R";
42"E1S_0_P12V_EN";
43"P12V_E1S_AVIN_PD_0";
44"P3V3_E1S_EN_0_R2";
45"P3V3_E1S_ILIMIT_0";
46"P3V3_E1S_PWRGD_0_R1";
47"P3V3_E1S_PWRGD_0_R";
48"E1S_0_P3V3_EN";
49"P3V3_E1S_DVDT_0";
50"P3V3_E1S_GATE_0_PU293";
%"UNIVERSAL_POWER"
"1","(975,-750)","2","pure_quanta_power","I10";
;
HDL_POWER"P3V3_AUX"
CDS_LIB"pure_quanta_power";
"A"31;
%"GND"
"1","(-2050,625)","0","pure_quanta_power","I12";
;
CDS_LIB"pure_quanta_power"
SIZE"1B"
HDL_POWER"GND";
"A<SIZE-1..0>\NAC"1;
%"Q_CAP"
"1","(-2050,975)","0","pure_quanta","I13";
;
LOCATION"PC2196"
$SEC"1"
CDS_SEC"1"
ROOM"E1S_P12V_MPS_MAM_BOM2"
MATERIAL"X7R"
PACK_TYPE"0402"
VOLTAGE"16V"
VALUE"0.22UF"
CDS_LIB"pure_quanta"
TOLERANCE"10%"
PART_NUMBER"CH4223K1B00";
"B"
$PN"2"1;
"A"
$PN"1"27;
%"GND"
"1","(-1625,550)","0","pure_quanta_power","I14";
;
CDS_LIB"pure_quanta_power"
SIZE"1B"
HDL_POWER"GND";
"A<SIZE-1..0>\NAC"2;
%"Q_RES"
"2","(-1625,850)","0","pure_quanta","I15";
;
LOCATION"PR3944"
$SEC"1"
CDS_SEC"1"
PACK_TYPE"0402LF"
ROOM"E1S_P12V_MPS_MAM_BOM2"
VALUE"46.4K"
WATTAGE"1/16W"
TOLERANCE"1%"
MATERIAL"CHIP"
CDS_LIB"pure_quanta"
PART_NUMBER"CS34642FB02";
"A"
$PN"1"28;
"B"
$PN"2"2;
%"GND"
"1","(-1275,350)","0","pure_quanta_power","I16";
;
SIZE"1B"
CDS_LIB"pure_quanta_power"
HDL_POWER"GND";
"A<SIZE-1..0>\NAC"3;
%"Q_CAP"
"1","(-1275,575)","0","pure_quanta","I17";
;
LOCATION"PC2341"
$SEC"1"
CDS_SEC"1"
PACK_TYPE"C0402"
VOLTAGE"50V"
MATERIAL"X7R"
VALUE"560PF"
ROOM"E1S_P12V_MPS_MAM_BOM2"
CDS_LIB"pure_quanta"
TOLERANCE"10%"
PART_NUMBER"CH1566K1B09";
"B"
$PN"2"3;
"A"
$PN"1"41;
%"Q_RES"
"2","(-1275,850)","0","pure_quanta","I18";
;
LOCATION"PR4541"
$SEC"1"
CDS_SEC"1"
PACK_TYPE"0402LF"
ROOM"E1S_P12V_MPS_MAM_BOM2"
WATTAGE"1/16W"
VALUE"20K"
MATERIAL"CHIP"
TOLERANCE"1%"
CDS_LIB"pure_quanta"
PART_NUMBER"CS32002FB06";
"A"
$PN"1"28;
"B"
$PN"2"41;
%"Q_RES"
"1","(-1275,1425)","0","pure_quanta","I19";
;
LOCATION"R3943"
$SEC"1"
CDS_SEC"1"
TOLERANCE"5%"
PACK_TYPE"0402LF"
MATERIAL"CHIP"
WATTAGE"1/16W"
VALUE"0"
ROOM"E1S_P12V_MPS_MAM_BOM2"
CDS_LIB"pure_quanta"
PART_NUMBER"CS00002JB13";
"B"
$PN"2"25;
"A"
$PN"1"42;
%"UNIVERSAL_GND"
"1","(325,-2025)","0","pure_quanta_power","I2";
;
CDS_LIB"pure_quanta_power"
HDL_POWER"GND";
"A"32;
%"GND"
"1","(-1150,1175)","0","pure_quanta_power","I20";
;
SIZE"1B"
CDS_LIB"pure_quanta_power"
HDL_POWER"GND";
"A<SIZE-1..0>\NAC"26;
%"GND"
"1","(-750,525)","0","pure_quanta_power","I21";
;
SIZE"1B"
CDS_LIB"pure_quanta_power"
HDL_POWER"GND";
"A<SIZE-1..0>\NAC"4;
%"Q_CAP"
"1","(-750,750)","0","pure_quanta","I22";
;
LOCATION"PC2281"
$SEC"1"
CDS_SEC"1"
ROOM"E1S_P12V_MPS_MAM_BOM2"
PACK_TYPE"C0402"
VOLTAGE"25V"
MATERIAL"X7R"
VALUE"0.047UF"
CDS_LIB"pure_quanta"
TOLERANCE"10%"
PART_NUMBER"CH3474K1B04";
"B"
$PN"2"4;
"A"
$PN"1"29;
%"GND"
"1","(-409,691)","0","pure_quanta_power","I23";
;
SIZE"1B"
CDS_LIB"pure_quanta_power"
HDL_POWER"GND";
"A<SIZE-1..0>\NAC"30;
%"Q_CAP"
"1","(-825,1825)","0","pure_quanta","I25";
;
LOCATION"PC2198"
$SEC"1"
CDS_SEC"1"
MATERIAL"X6S"
PACK_TYPE"C0402"
VALUE"1UF"
VOLTAGE"25V"
ROOM"E1S_P12V_MPS_MAM_BOM2"
CDS_LIB"pure_quanta"
TOLERANCE"10%"
PART_NUMBER"CH5104KEB02";
"B"
$PN"2"5;
"A"
$PN"1"19;
%"GND"
"1","(-825,1600)","0","pure_quanta_power","I26";
;
CDS_LIB"pure_quanta_power"
SIZE"1B"
HDL_POWER"GND";
"A<SIZE-1..0>\NAC"5;
%"UNIVERSAL_POWER"
"1","(-825,2175)","0","pure_quanta_power","I27";
;
HDL_POWER"P12V_AUX"
CDS_LIB"pure_quanta_power";
"A"19;
%"UNIVERSAL_GND"
"1","(3050,-2150)","0","pure_quanta_power","I28";
;
CDS_LIB"pure_quanta_power"
HDL_POWER"GND";
"A"33;
%"UNIVERSAL_GND"
"1","(1550,-2025)","0","pure_quanta_power","I29";
;
CDS_LIB"pure_quanta_power"
HDL_POWER"GND";
"A"6;
%"Q_CAP"
"1","(325,-1650)","0","pure_quanta","I3";
;
LOCATION"PC2197"
$SEC"1"
CDS_SEC"1"
PACK_TYPE"0402"
MATERIAL"NPO"
VOLTAGE"50V"
ROOM"E1S_P3V3_BOM2"
VALUE"39PF"
CDS_LIB"pure_quanta"
TOLERANCE"5%"
PART_NUMBER"CH03906JB06";
"B"
$PN"2"32;
"A"
$PN"1"40;
%"Q_CAP"
"1","(1550,-1725)","0","pure_quanta","I30";
;
LOCATION"PC2201"
$SEC"1"
CDS_SEC"1"
VALUE"0.068UF"
VOLTAGE"16V"
MATERIAL"X7R"
PACK_TYPE"0402"
ROOM"E1S_P3V3_BOM2"
CDS_LIB"pure_quanta"
TOLERANCE"10%"
PART_NUMBER"CH3683K1B09";
"B"
$PN"2"6;
"A"
$PN"1"49;
%"MP5016GQHLZ"
"1","(2200,-1400)","0","pure_quanta","I31";
;
LOCATION"PU293"
$SEC"1"
CDS_SEC"1"
MATERIAL"IC"
VALUE"MP5016GQH-L-Z"
PART_TYPE"SMLF"
ROOM"E1S_P3V3_BOM2"
CDS_LIB"pure_quanta"
CDS_LMAN_SYM_OUTLINE"-250,200,250,-200"
NEEDS_NO_SIZE"TRUE"
PART_NUMBER"AL005016007";
"SOURCE"
$PN"6_7"8;
"GATE"
$PN"8"50;
"DV_DT"
$PN"10"49;
"VCC"
$PN"1_2"31;
"GND"
$PN"3"33;
"ILIMIT"
$PN"4"45;
"MODE"
$PN"5"40;
"EN"
$PN"9"44;
%"Q_CAP"
"1","(3050,-1800)","0","pure_quanta","I32";
;
LOCATION"PC2203"
$SEC"1"
CDS_SEC"1"
TOLERANCE"5%"
ROOM"E1S_P3V3_BOM2"
VOLTAGE"50V"
MATERIAL"X7R"
PACK_TYPE"0402"
VALUE"100PF"
CDS_LIB"pure_quanta"
PART_NUMBER"CH11006JB18";
"B"
$PN"2"33;
"A"
$PN"1"50;
%"UNIVERSAL_GND"
"1","(3650,-1925)","0","pure_quanta_power","I33";
;
CDS_LIB"pure_quanta_power"
HDL_POWER"GND";
"A"7;
%"Q_CAP"
"1","(3650,-1575)","0","pure_quanta","I34";
;
LOCATION"PC2204"
$SEC"1"
CDS_SEC"1"
PACK_TYPE"C0805"
VOLTAGE"16V"
VALUE"10UF"
MATERIAL"X6S"
ROOM"E1S_P3V3_BOM2"
TOLERANCE"10%"
CDS_LIB"pure_quanta"
PART_NUMBER"CH6103KEA01";
"B"
$PN"2"7;
"A"
$PN"1"8;
%"UNIVERSAL_POWER"
"1","(3650,-925)","2","pure_quanta_power","I35";
;
HDL_POWER"P3V3_E1S_0_R"
CDS_LIB"pure_quanta_power";
"A"8;
%"Q_RES"
"2","(675,550)","0","pure_quanta","I36";
;
LOCATION"PR3949"
$SEC"1"
CDS_SEC"1"
ROOM"E1S_P12V_MPS_MAM_BOM2"
MATERIAL"CHIP"
VALUE"56K"
TOLERANCE"1%"
WATTAGE"1/16W"
PACK_TYPE"0402LF"
CDS_LIB"pure_quanta"
PART_NUMBER"CS35602FB00";
"A"
$PN"1"24;
"B"
$PN"2"34;
%"Q_RES"
"2","(525,2000)","0","pure_quanta","I37";
;
LOCATION"R3948"
$SEC"1"
CDS_SEC"1"
ROOM"E1S_P12V_MPS_MAM_BOM2"
PACK_TYPE"0402LF"
TOLERANCE"1%"
VALUE"10K"
WATTAGE"1/16W"
MATERIAL"CHIP"
CDS_LIB"pure_quanta"
PART_NUMBER"CS31002FB08";
"A"
$PN"1"10;
"B"
$PN"2"22;
%"GND"
"1","(1125,150)","0","pure_quanta_power","I38";
;
SIZE"1B"
CDS_LIB"pure_quanta_power"
HDL_POWER"GND";
"A<SIZE-1..0>\NAC"34;
%"Q_CAP"
"1","(1125,550)","0","pure_quanta","I39";
;
LOCATION"PC2202"
$SEC"1"
CDS_SEC"1"
ROOM"E1S_P12V_MPS_MAM_BOM2"
PACK_TYPE"C0402"
MATERIAL"X7R"
VOLTAGE"50V"
VALUE"100NF"
TOLERANCE"10%"
CDS_LIB"pure_quanta"
PART_NUMBER"CH4106K1B01";
"B"
$PN"2"34;
"A"
$PN"1"24;
%"Q_RES"
"2","(675,-1650)","0","pure_quanta","I4";
;
LOCATION"PR3945"
$SEC"1"
CDS_SEC"1"
VALUE"71.5K"
MATERIAL"CHIP"
TOLERANCE"1%"
PACK_TYPE"0402LF"
ROOM"E1S_P3V3_BOM2"
WATTAGE"1/16W"
CDS_LIB"pure_quanta"
PART_NUMBER"CS37152FB05";
"A"
$PN"1"40;
"B"
$PN"2"32;
%"Q_RES"
"1","(1100,925)","0","pure_quanta","I40";
;
LOCATION"PR3951"
$SEC"1"
CDS_SEC"1"
ROOM"E1S_P12V_MPS_MAM_BOM2"
PACK_TYPE"0402LF"
VALUE"10K"
WATTAGE"1/16W"
TOLERANCE"1%"
MATERIAL"CHIP"
CDS_LIB"pure_quanta"
PART_NUMBER"CS31002FB08";
"B"
$PN"2"9;
"A"
$PN"1"23;
%"VCCAUX15"
"1","(1675,975)","0","pure_quanta_power","I41";
;
HDL_POWER"P3V3_AUX"
CDS_LIB"pure_quanta_power";
"A"9;
%"Q_RES"
"2","(1050,1400)","0","pure_quanta","I42";
;
LOCATION"PR3950"
$SEC"1"
CDS_SEC"1"
TOLERANCE"1%"
WATTAGE"1/16W"
VALUE"100"
MATERIAL"EMPTY"
PACK_TYPE"0402LF"
ROOM"E1S_P12V_MPS_MAM_BOM2"
CDS_LIB"pure_quanta"
PART_NUMBER"CS11002FB07";
"A"
$PN"1"18;
"B"
$PN"2"20;
%"Q_RES"
"2","(1650,1400)","0","pure_quanta","I45";
;
LOCATION"PR3952"
$SEC"1"
CDS_SEC"1"
ROOM"E1S_P12V_MPS_MAM_BOM2"
TOLERANCE"1%"
PACK_TYPE"0402LF"
VALUE"71.5K"
MATERIAL"EMPTY"
CDS_LIB"pure_quanta"
WATTAGE"1/16W"
PART_NUMBER"CS37152FB05";
"A"
$PN"1"18;
"B"
$PN"2"21;
%"VCCAUX15"
"1","(525,2200)","0","pure_quanta_power","I46";
;
HDL_POWER"P3V3_AUX"
CDS_LIB"pure_quanta_power";
"A"10;
%"Q_RES"
"1","(2475,225)","0","pure_quanta","I47";
;
LOCATION"R3956"
$SEC"1"
CDS_SEC"1"
MATERIAL"EMPTY"
ROOM"E1S_P12V_MPS_TIC_BOM3"
VALUE"0"
PACK_TYPE"0402LF"
WATTAGE"1/16W"
TOLERANCE"5%"
CDS_LIB"pure_quanta"
PART_NUMBER"CS00002JB13";
"B"
$PN"2"39;
"A"
$PN"1"24;
%"Q_RES"
"1","(2475,400)","0","pure_quanta","I48";
;
LOCATION"R3955"
$SEC"1"
CDS_SEC"1"
WATTAGE"1/16W"
PACK_TYPE"0402LF"
MATERIAL"CHIP"
ROOM"E1S_P12V_MPS_MAM_BOM2"
VALUE"0"
TOLERANCE"5%"
CDS_LIB"pure_quanta"
PART_NUMBER"CS00002JB13";
"B"
$PN"2"38;
"A"
$PN"1"24;
%"Q_RES"
"2","(2050,900)","0","pure_quanta","I49";
;
LOCATION"PR3954"
$SEC"1"
CDS_SEC"1"
PACK_TYPE"0402LF"
TOLERANCE"1%"
VALUE"10K"
MATERIAL"CHIP"
WATTAGE"1/16W"
ROOM"E1S_P12V_MPS_MAM_BOM2"
CDS_LIB"pure_quanta"
PART_NUMBER"CS31002FB08";
"A"
$PN"1"21;
"B"
$PN"2"35;
%"Q_RES"
"1","(750,-1350)","0","pure_quanta","I5";
;
LOCATION"R3946"
$SEC"1"
CDS_SEC"1"
WATTAGE"1/16W"
VALUE"0"
MATERIAL"CHIP"
TOLERANCE"5%"
PACK_TYPE"0402LF"
ROOM"E1S_P3V3_BOM2"
CDS_LIB"pure_quanta"
PART_NUMBER"CS00002JB13";
"B"
$PN"2"44;
"A"
$PN"1"48;
%"GND"
"1","(2250,575)","0","pure_quanta_power","I50";
;
CDS_LIB"pure_quanta_power"
SIZE"1B"
HDL_POWER"GND";
"A<SIZE-1..0>\NAC"35;
%"Q_CAP"
"1","(2575,900)","0","pure_quanta","I51";
;
LOCATION"PC2205"
$SEC"1"
CDS_SEC"1"
ROOM"E1S_P12V_MPS_MAM_BOM2"
PACK_TYPE"C0603"
VOLTAGE"16V"
TOLERANCE"20%"
VALUE"2.2UF"
MATERIAL"X7R"
CDS_LIB"pure_quanta"
PART_NUMBER"CH5223M1900";
"B"
$PN"2"35;
"A"
$PN"1"43;
%"Q_RES"
"2","(2050,1325)","0","pure_quanta","I52";
;
LOCATION"PR3953"
$SEC"1"
CDS_SEC"1"
VALUE"120K"
TOLERANCE"1%"
PACK_TYPE"0402LF"
MATERIAL"CHIP"
WATTAGE"1/16W"
ROOM"E1S_P12V_MPS_MAM_BOM2"
CDS_LIB"pure_quanta"
PART_NUMBER"CS41202FB05";
"A"
$PN"1"36;
"B"
$PN"2"21;
%"UNIVERSAL_POWER"
"1","(2475,1625)","0","pure_quanta_power","I53";
;
HDL_POWER"P12V_AUX"
CDS_LIB"pure_quanta_power";
"A"36;
%"Q_RES"
"2","(2575,1325)","0","pure_quanta","I54";
;
LOCATION"PR3957"
$SEC"1"
CDS_SEC"1"
MATERIAL"CHIP"
WATTAGE"1/10W"
TOLERANCE"1%"
PACK_TYPE"0603LF"
VALUE"49.9"
ROOM"E1S_P12V_MPS_MAM_BOM2"
CDS_LIB"pure_quanta"
PART_NUMBER"CS04993F909";
"A"
$PN"1"36;
"B"
$PN"2"43;
%"GND"
"1","(2925,1475)","0","pure_quanta_power","I55";
;
SIZE"1B"
CDS_LIB"pure_quanta_power"
HDL_POWER"GND";
"A<SIZE-1..0>\NAC"11;
%"Q_CAP"
"1","(2925,1750)","2","pure_quanta","I56";
;
LOCATION"PC2206"
$SEC"1"
CDS_SEC"1"
TOLERANCE"10%"
MATERIAL"X7R"
PACK_TYPE"0402"
VOLTAGE"25V"
ROOM"E1S_P12V_MPS_MAM_BOM2"
VALUE"0.1UF"
CDS_LIB"pure_quanta"
PART_NUMBER"CH4104K1B00";
"B"
$PN"2"11;
"A"
$PN"1"18;
%"UNIVERSAL_POWER"
"1","(2925,2025)","2","pure_quanta_power","I57";
;
HDL_POWER"P12V_E1S_0"
CDS_LIB"pure_quanta_power";
"A"18;
%"Q_RES"
"1","(1000,-1700)","1","pure_quanta","I6";
;
LOCATION"PR3947"
$SEC"1"
CDS_SEC"1"
PACK_TYPE"0402LF"
TOLERANCE"1%"
VALUE"2.8K"
MATERIAL"CHIP"
ROOM"E1S_P3V3_BOM2"
WATTAGE"1/16W"
CDS_LIB"pure_quanta"
PART_NUMBER"CS22802FB04";
"B"
$PN"2"45;
"A"
$PN"1"15;
%"UNIVERSAL_GND"
"1","(-4000,-2600)","0","pure_quanta_power","I63";
;
CDS_LIB"pure_quanta_power"
HDL_POWER"GND";
"A"12;
%"Q_CAP"
"1","(-4000,-2250)","2","pure_quanta","I64";
;
LOCATION"C8010"
$SEC"1"
CDS_SEC"1"
TOLERANCE"10%"
VALUE"0.1UF"
VOLTAGE"25V"
MATERIAL"X7R"
PACK_TYPE"0402"
ROOM"E1S_P3V3_BOM2"
CDS_LIB"pure_quanta"
PART_NUMBER"CH4104K1B00";
"B"
$PN"2"12;
"A"
$PN"1"37;
%"APX80929SAG7"
"1","(-3325,-2000)","2","pure_quanta","I65";
;
LOCATION"U8003"
$SEC"1"
CDS_SEC"1"
ROOM"E1S_P3V3_BOM2"
MATERIAL"IC"
VALUE"APX809-29SAG-7"
PART_TYPE"SMLF"
CDS_LIB"pure_quanta"
CDS_LMAN_SYM_OUTLINE"-225,200,225,-200"
NEEDS_NO_SIZE"TRUE"
PART_NUMBER"AL080929000";
"GND"
$PN"1"14;
"RESET_L \B"
$PN"2"46;
"VCC"
$PN"3"37;
%"UNIVERSAL_GND"
"1","(-2250,-2875)","0","pure_quanta_power","I67";
;
CDS_LIB"pure_quanta_power"
HDL_POWER"GND";
"A"13;
%"Q_RES"
"2","(-2250,-2475)","0","pure_quanta","I68";
;
LOCATION"R8099"
$SEC"1"
CDS_SEC"1"
TOLERANCE"1%"
VALUE"100K"
PACK_TYPE"0402LF"
MATERIAL"CHIP"
WATTAGE"1/16W"
ROOM"E1S_P3V3_BOM2"
CDS_LIB"pure_quanta"
PART_NUMBER"CS41002FB09";
"A"
$PN"1"46;
"B"
$PN"2"13;
%"UNIVERSAL_GND"
"1","(-2775,-2000)","0","pure_quanta_power","I69";
;
CDS_LIB"pure_quanta_power"
HDL_POWER"GND";
"A"14;
%"UNIVERSAL_GND"
"1","(1000,-2025)","0","pure_quanta_power","I7";
;
CDS_LIB"pure_quanta_power"
HDL_POWER"GND";
"A"15;
%"Q_RES"
"2","(-2100,-1600)","0","pure_quanta","I70";
;
LOCATION"R8098"
$SEC"1"
CDS_SEC"1"
PACK_TYPE"0402LF"
MATERIAL"EMPTY"
TOLERANCE"5%"
WATTAGE"1/16W"
VALUE"10K"
ROOM"E1S_P3V3_BOM2"
CDS_LIB"pure_quanta"
PART_NUMBER"CS31002JB08";
"A"
$PN"1"16;
"B"
$PN"2"46;
%"Q_RES"
"1","(-1725,-2100)","0","pure_quanta","I71";
;
LOCATION"R8100"
$SEC"1"
CDS_SEC"1"
PACK_TYPE"0402LF"
TOLERANCE"5%"
MATERIAL"CHIP"
VALUE"0"
WATTAGE"1/16W"
ROOM"E1S_P3V3_BOM2"
CDS_LIB"pure_quanta"
PART_NUMBER"CS00002JB13";
"B"
$PN"2"47;
"A"
$PN"1"46;
%"UNIVERSAL_POWER"
"1","(-4000,-1650)","2","pure_quanta_power","I74";
;
HDL_POWER"P3V3_E1S_0_R"
CDS_LIB"pure_quanta_power";
"A"37;
%"UNIVERSAL_POWER"
"1","(-2100,-1225)","2","pure_quanta_power","I75";
;
HDL_POWER"P3V3_E1S_0_R"
CDS_LIB"pure_quanta_power";
"A"16;
%"RS31312R"
"1","(50,1300)","0","pure_quanta","I76";
;
LOCATION"PU292"
SEC"1"
VALUE"RS31312R"
PART_TYPE"SMLF"
MATERIAL"IC"
ROOM"E1S_P12V_MPS_MAM_BOM2"
CDS_LIB"pure_quanta"
NEEDS_NO_SIZE"TRUE"
CDS_LMAN_SYM_OUTLINE"-250,525,250,-525"
SEC_TYPE""
PART_NUMBER"AL031312000";
"GND"
$PN"7"30;
"SS"
$PN"6"29;
"ISET"
$PN"5"28;
"TIMER"
$PN"4"27;
"ENTM"
$PN"3"26;
"LOADEN"
$PN"2"26;
"EN"
$PN"1"25;
"VIN_26"
$PN"26"19;
"VIN_25"
$PN"25"19;
"VIN_24"
$PN"24"19;
"VIN_23"
$PN"23"19;
"IMON"
$PN"8"24;
"FLTB"
$PN"9"23;
"PG"
$PN"10"22;
"OV"
$PN"11"21;
"VOUT_13"
$PN"13"18;
"AVIN"
$PN"12"20;
"VOUT_14"
$PN"14"18;
"VOUT_15"
$PN"15"18;
"VOUT_16"
$PN"16"18;
"VOUT_17"
$PN"17"18;
"VOUT_18"
$PN"18"18;
"VOUT_19"
$PN"19"18;
"VIN_21_22"
$PN"21_22"19;
"VOUT_20"
$PN"20"18;
%"UNIVERSAL_GND"
"1","(975,-1300)","0","pure_quanta_power","I8";
;
CDS_LIB"pure_quanta_power"
HDL_POWER"GND";
"A"17;
%"Q_CAP"
"1","(975,-1075)","0","pure_quanta","I9";
;
LOCATION"PC2200"
$SEC"1"
CDS_SEC"1"
PACK_TYPE"C0402"
MATERIAL"X6S"
VALUE"1UF"
VOLTAGE"25V"
ROOM"E1S_P3V3_BOM2"
CDS_LIB"pure_quanta"
TOLERANCE"10%"
PART_NUMBER"CH5104KEB02";
"B"
$PN"2"17;
"A"
$PN"1"31;
END.
